G04 ================== begin FILE IDENTIFICATION RECORD ==================*
G04 Layout Name:  12433-1M.brd*
G04 Film Name:    P_OUTLINE*
G04 File Format:  Gerber RS274X*
G04 File Origin:  Cadence Allegro 16.2-S037*
G04 Origin Date:  Fri Dec 07 18:55:02 2012*
G04 *
G04 Layer:  BOARD GEOMETRY/PANEL_OUTLINE*
G04 *
G04 Offset:    (0.00 0.00)*
G04 Mirror:    No*
G04 Mode:      Positive*
G04 Rotation:  0*
G04 FullContactRelief:  No*
G04 UndefLineWidth:     6.00*
G04 ================== end FILE IDENTIFICATION RECORD ====================*
%FSLAX35Y35*MOIN*%
%IR0*IPPOS*OFA0.00000B0.00000*MIA0B0*SFA1.00000B1.00000*%
%ADD10C,.006*%
G75*
%LPD*%
G75*
G54D10*
G01X-242126Y15000D02*
G03X-227126Y0I15000J0D01*
G01X-242126Y1953504D02*
Y15000D01*
G01X-215453Y19685D02*
G03I-6988J0D01*
G01X-84646Y0D02*
X-227126D01*
G01X-215453Y19685D02*
G03I-6988J0D01*
G01D02*
G03I-6988J0D01*
G01X-227126Y1968504D02*
G03X-242126Y1953504I0J-15000D01*
G01X-215453Y1948819D02*
G03I-6988J0D01*
G01X-84638Y1968504D02*
X-227126D01*
G01X-215453Y1948819D02*
G03I-6988J0D01*
G01D02*
G03I-6988J0D01*
G01X-222441Y39370D02*
G03X-214567Y31496I7874J0D01*
G01X-206693D02*
X-214567D01*
G01X-175984D02*
X-84646D01*
G01X-206693D02*
G03Y39370I0J3937D01*
G01X-175984D02*
G03Y31496I0J-3937D01*
G01X-206693D02*
X-214567D01*
G01X-84646Y0D02*
X-199567D01*
G01X-175984Y31496D02*
X-84646D01*
G01X-206693D02*
G03Y39370I0J3937D01*
G01X-175984D02*
G03Y31496I0J-3937D01*
G01X-222441Y169326D02*
Y39370D01*
G01X-214567Y43307D02*
G03X-210630Y39370I3937J0D01*
G01X-214567Y43307D02*
G03X-210630Y39370I3937J0D01*
G01X-80709D02*
X-210630D01*
G01X-80709D02*
X-210630D01*
G01X-214567Y43307D02*
Y1925197D01*
G01Y43307D02*
Y1925197D01*
G01Y149606D02*
Y43307D01*
G01Y149606D02*
Y43272D01*
G01Y169326D02*
G03X-222441I-3937J0D01*
G01X-214567D02*
G03X-222441I-3937J0D01*
G01X-214567Y1807087D02*
Y161417D01*
G01Y1807087D02*
Y161417D01*
G01X-222441Y436255D02*
Y200034D01*
G01D02*
G03X-214567I3937J0D01*
G01X-222441D02*
G03X-214567I3937J0D01*
G01Y436255D02*
G03X-222441I-3937J0D01*
G01X-214567D02*
G03X-222441I-3937J0D01*
G01Y703184D02*
Y466963D01*
G01D02*
G03X-214567I3937J0D01*
G01X-222441D02*
G03X-214567I3937J0D01*
G01X-222441Y970901D02*
Y733892D01*
G01X-214567Y703184D02*
G03X-222441I-3937J0D01*
G01Y733892D02*
G03X-214567I3937J0D01*
G01Y703184D02*
G03X-222441I-3937J0D01*
G01Y733892D02*
G03X-214567I3937J0D01*
G01X-222441Y1234681D02*
Y997672D01*
G01X-214567Y970901D02*
G03X-222441I-3937J0D01*
G01Y997672D02*
G03X-214567I3937J0D01*
G01Y970901D02*
G03X-222441I-3937J0D01*
G01Y997672D02*
G03X-214567I3937J0D01*
G01X-222441Y1265389D02*
G03X-214567I3937J0D01*
G01Y1234681D02*
G03X-222441I-3937J0D01*
G01Y1265389D02*
G03X-214567I3937J0D01*
G01Y1234681D02*
G03X-222441I-3937J0D01*
G01Y1501610D02*
Y1265389D01*
G01X-214567Y1501610D02*
G03X-222441I-3937J0D01*
G01X-214567D02*
G03X-222441I-3937J0D01*
G01Y1768539D02*
Y1532318D01*
G01D02*
G03X-214567I3937J0D01*
G01X-222441D02*
G03X-214567I3937J0D01*
G01Y1768539D02*
G03X-222441I-3937J0D01*
G01X-214567D02*
G03X-222441I-3937J0D01*
G01Y1799247D02*
G03X-214567I3937J0D01*
G01X-222441D02*
G03X-214567I3937J0D01*
G01X-222441Y1929134D02*
Y1799247D01*
G01X-214567Y1818898D02*
Y1925231D01*
G01Y1818898D02*
Y1925231D01*
G01X-210630Y1929134D02*
G03X-214567Y1925197I0J-3937D01*
G01X-210630Y1929134D02*
G03X-214567Y1925197I0J-3937D01*
G01Y1937008D02*
G03X-222441Y1929134I0J-7874D01*
G01X-210630D02*
X-80709D01*
G01X-210630D02*
X-80709D01*
G01X-175984Y1937008D02*
X-84638D01*
G01X-214567D02*
X-206693D01*
G01X-175984D02*
G03Y1929134I0J-3937D01*
G01X-206693D02*
G03Y1937008I0J3937D01*
G01X-84638Y1968504D02*
X-199567D01*
G01X-175984Y1937008D02*
X-84638D01*
G01X-214567D02*
X-206693D01*
G01X-175984D02*
G03Y1929134I0J-3937D01*
G01X-206693D02*
G03Y1937008I0J3937D01*
G01X-76772Y3937D02*
G03X-72835Y0I3937J0D01*
G01X-76772Y35433D02*
G03X-80709Y39370I-3937J0D01*
G01X-76772Y35433D02*
G03X-80709Y39370I-3937J0D01*
G01X-76772Y3937D02*
G03X-72835Y0I3937J0D01*
G01X-76772Y3937D02*
Y35433D01*
G01Y3937D02*
Y35433D01*
G01Y3937D02*
G03X-72835Y0I3937J0D01*
G01X-84646Y7874D02*
Y0D01*
G01X-76772Y7874D02*
G03X-84646I-3937J0D01*
G01Y31496D02*
G03X-76772I3937J0D01*
G01Y3937D02*
G03X-72835Y0I3937J0D01*
G01X-84646Y7874D02*
Y0D01*
G01X-76772Y7874D02*
G03X-84646I-3937J0D01*
G01Y31496D02*
G03X-76772I3937J0D01*
G01X-76763Y1937008D02*
G03X-84638I-3937J0D01*
G01X-80709Y1929134D02*
G03X-76772Y1933071I0J3937D01*
G01X-80709Y1929134D02*
G03X-76772Y1933071I0J3937D01*
G01X-72835Y1968504D02*
G03X-76772Y1964567I0J-3937D01*
G01X-72835Y1968504D02*
G03X-76772Y1964567I0J-3937D01*
G01Y1933071D02*
Y1964567D01*
G01Y1933071D02*
Y1964567D01*
G01X-72835Y1968504D02*
G03X-76772Y1964567I0J-3937D01*
G01X-84638Y1960889D02*
Y1968504D01*
G01Y1960889D02*
G03X-76763I3938J0D01*
G01X-72835Y1968504D02*
G03X-76772Y1964567I0J-3937D01*
G01X-84638Y1960889D02*
Y1968504D01*
G01Y1960889D02*
G03X-76763I3938J0D01*
G01X-11811Y0D02*
X-72835D01*
G01X-11811D02*
X-72835D01*
G01D02*
X-11811D01*
G01X-72835D02*
X-11811D01*
G01X-72835Y1968504D02*
X-11811D01*
G01X-72835D02*
X-11811D01*
G01D02*
X-72835D01*
G01X-11811D02*
X-72835D01*
G01X-11811Y0D02*
G03X-7874Y3937I0J3937D01*
G01X-11811Y0D02*
G03X-7874Y3937I0J3937D01*
G01Y43110D02*
Y3937D01*
G01Y43110D02*
Y3937D01*
G01X0D02*
G03X3937Y0I3937J0D01*
G01X0Y3937D02*
G03X3937Y0I3937J0D01*
G01X0Y3937D02*
Y43110D01*
G01Y3937D02*
Y43110D01*
G01X64961Y0D02*
X3937D01*
G01X64961D02*
X3937D01*
G01X0Y3937D02*
G03X3937Y0I3937J0D01*
G01X0Y1964567D02*
Y3937D01*
G01X3937Y0D02*
X64961D01*
G01X-7874Y3937D02*
Y1964567D01*
G01X-11811Y0D02*
G03X-7874Y3937I0J3937D01*
G01X0Y11811D02*
G03X-7874I-3937J0D01*
G01X0Y3937D02*
G03X3937Y0I3937J0D01*
G01X0Y1964567D02*
Y3937D01*
G01X3937Y0D02*
X64961D01*
G01X-7874Y3937D02*
Y1964567D01*
G01X-11811Y0D02*
G03X-7874Y3937I0J3937D01*
G01X0Y11811D02*
G03X-7874I-3937J0D01*
G01Y93110D02*
Y43110D01*
G01Y93110D02*
Y43110D01*
G01X0D02*
Y93110D01*
G01Y43110D02*
Y93110D01*
G01X-7874Y42520D02*
G03X0I3937J0D01*
G01X-7874D02*
G03X0I3937J0D01*
G01X-7874Y214764D02*
Y93110D01*
G01Y214764D02*
Y93110D01*
G01X0D02*
Y214764D01*
G01Y93110D02*
Y214764D01*
G01X-7874Y226968D02*
Y214764D01*
G01Y226968D02*
Y214764D01*
G01Y342461D02*
Y226968D01*
G01Y342461D02*
Y226968D01*
G01X0Y226969D02*
Y342461D01*
G01Y226969D02*
Y342461D01*
G01Y214764D02*
Y226969D01*
G01Y214764D02*
Y226969D01*
G01Y278740D02*
G03X-7874I-3937J0D01*
G01X0D02*
G03X-7874I-3937J0D01*
G01Y354665D02*
Y342461D01*
G01Y354665D02*
Y342461D01*
G01X0D02*
Y354665D01*
G01Y342461D02*
Y354665D01*
G01X-7874Y309449D02*
G03X0I3937J0D01*
G01X-7874D02*
G03X0I3937J0D01*
G01X-7874Y476339D02*
Y354665D01*
G01Y476339D02*
Y354665D01*
G01X0D02*
Y476339D01*
G01Y354665D02*
Y476339D01*
G01X-7874Y526339D02*
Y476339D01*
G01Y526339D02*
Y476339D01*
G01X0D02*
Y526339D01*
G01Y476339D02*
Y526339D01*
G01X-7874Y736181D02*
Y526339D01*
G01Y736181D02*
Y526339D01*
G01X0D02*
Y736181D01*
G01Y526339D02*
Y736181D01*
G01Y545669D02*
G03X-7874I-3937J0D01*
G01X0D02*
G03X-7874I-3937J0D01*
G01Y576378D02*
G03X0I3937J0D01*
G01X-7874D02*
G03X0I3937J0D01*
G01X-7874Y786181D02*
Y736181D01*
G01Y786181D02*
Y736181D01*
G01X0D02*
Y786181D01*
G01Y736181D02*
Y786181D01*
G01X-7874Y907815D02*
Y786181D01*
G01Y907815D02*
Y786181D01*
G01X0D02*
Y907815D01*
G01Y786181D02*
Y907815D01*
G01Y831496D02*
G03X-7874I-3937J0D01*
G01X0D02*
G03X-7874I-3937J0D01*
G01Y862205D02*
G03X0I3937J0D01*
G01X-7874D02*
G03X0I3937J0D01*
G01X-7874Y920020D02*
Y907815D01*
G01Y920020D02*
Y907815D01*
G01Y1048484D02*
Y920020D01*
G01Y1048484D02*
Y920020D01*
G01X0D02*
Y1048484D01*
G01Y920020D02*
Y1048484D01*
G01Y907815D02*
Y920020D01*
G01Y907815D02*
Y920020D01*
G01X-7874Y1060689D02*
Y1048484D01*
G01Y1060689D02*
Y1048484D01*
G01X0D02*
Y1060689D01*
G01Y1048484D02*
Y1060689D01*
G01X-7874Y1182323D02*
Y1060689D01*
G01Y1182323D02*
Y1060689D01*
G01X0D02*
Y1182323D01*
G01Y1060689D02*
Y1182323D01*
G01Y1106299D02*
G03X-7874I-3937J0D01*
G01X0D02*
G03X-7874I-3937J0D01*
G01Y1137008D02*
G03X0I3937J0D01*
G01X-7874D02*
G03X0I3937J0D01*
G01X-7874Y1232323D02*
Y1182323D01*
G01Y1232323D02*
Y1182323D01*
G01X0D02*
Y1232323D01*
G01Y1182323D02*
Y1232323D01*
G01X-7874Y1442165D02*
Y1232323D01*
G01Y1442165D02*
Y1232323D01*
G01X0D02*
Y1442165D01*
G01Y1232323D02*
Y1442165D01*
G01Y1392126D02*
G03X-7874I-3937J0D01*
G01X0D02*
G03X-7874I-3937J0D01*
G01Y1492165D02*
Y1442165D01*
G01Y1492165D02*
Y1442165D01*
G01X0D02*
Y1492165D01*
G01Y1442165D02*
Y1492165D01*
G01X-7874Y1422835D02*
G03X0I3937J0D01*
G01X-7874D02*
G03X0I3937J0D01*
G01X-7874Y1613839D02*
Y1492165D01*
G01Y1613839D02*
Y1492165D01*
G01X0D02*
Y1613839D01*
G01Y1492165D02*
Y1613839D01*
G01X-7874Y1626043D02*
Y1613839D01*
G01Y1626043D02*
Y1613839D01*
G01X0D02*
Y1626043D01*
G01Y1613839D02*
Y1626043D01*
G01X-7874Y1741535D02*
Y1626043D01*
G01Y1741535D02*
Y1626043D01*
G01X0D02*
Y1741535D01*
G01Y1626043D02*
Y1741535D01*
G01Y1659055D02*
G03X-7874I-3937J0D01*
G01X0D02*
G03X-7874I-3937J0D01*
G01Y1689764D02*
G03X0I3937J0D01*
G01X-7874D02*
G03X0I3937J0D01*
G01X-7874Y1753740D02*
Y1741535D01*
G01Y1753740D02*
Y1741535D01*
G01Y1875394D02*
Y1753740D01*
G01Y1875394D02*
Y1753740D01*
G01X0D02*
Y1875394D01*
G01Y1753740D02*
Y1875394D01*
G01Y1741535D02*
Y1753740D01*
G01Y1741535D02*
Y1753740D01*
G01X-7874Y1925394D02*
Y1875394D01*
G01Y1925394D02*
Y1875394D01*
G01X0D02*
Y1925394D01*
G01Y1875394D02*
Y1925394D01*
G01X-7874Y1964567D02*
Y1925394D01*
G01Y1964567D02*
Y1925394D01*
G01X0D02*
Y1964567D01*
G01Y1925394D02*
Y1964567D01*
G01Y1925984D02*
G03X-7874I-3937J0D01*
G01X0D02*
G03X-7874I-3937J0D01*
G01Y1964567D02*
G03X-11811Y1968504I-3937J0D01*
G01X-7874Y1964567D02*
G03X-11811Y1968504I-3937J0D01*
G01X3937D02*
G03X0Y1964567I0J-3937D01*
G01X3937Y1968504D02*
G03X0Y1964567I0J-3937D01*
G01X3937Y1968504D02*
X64961D01*
G01X3937D02*
X64961D01*
G01X3937D02*
G03X0Y1964567I0J-3937D01*
G01X64961Y1968504D02*
X3937D01*
G01X-7874Y1964567D02*
G03X-11811Y1968504I-3937J0D01*
G01X-7874Y1956693D02*
G03X0I3937J0D01*
G01X3937Y1968504D02*
G03X0Y1964567I0J-3937D01*
G01X64961Y1968504D02*
X3937D01*
G01X-7874Y1964567D02*
G03X-11811Y1968504I-3937J0D01*
G01X-7874Y1956693D02*
G03X0I3937J0D01*
G01X168110Y31496D02*
X76763D01*
G01X72835Y39370D02*
G03X68898Y35433I0J-3937D01*
G01X72835Y39370D02*
G03X68898Y35433I0J-3937D01*
G01X64961Y0D02*
G03X68898Y3937I0J3937D01*
G01X64961Y0D02*
G03X68898Y3937I0J3937D01*
G01Y35433D02*
Y3937D01*
G01Y35433D02*
Y3937D01*
G01X72835Y39370D02*
G03X68898Y35433I0J-3937D01*
G01Y3937D02*
Y35485D01*
G01X64961Y0D02*
G03X68898Y3937I0J3937D01*
G01X76763D02*
G03X80700Y0I3937J0D01*
G01X76763Y7615D02*
Y3937D01*
G01X168110Y31496D02*
X76763D01*
G01Y7615D02*
G03X68889I-3937J0D01*
G01Y31496D02*
G03X76763I3937J0D01*
G01X72835Y39370D02*
G03X68898Y35433I0J-3937D01*
G01Y3937D02*
Y35485D01*
G01X64961Y0D02*
G03X68898Y3937I0J3937D01*
G01X76763D02*
G03X80700Y0I3937J0D01*
G01X76763Y7615D02*
Y3937D01*
G01X168110Y31496D02*
X76763D01*
G01Y7615D02*
G03X68889I-3937J0D01*
G01Y31496D02*
G03X76763I3937J0D01*
G01X202756Y39370D02*
X72835D01*
G01X202756D02*
X72835D01*
G01D02*
X202756D01*
G01X72835D02*
X202756D01*
G01X68898Y1964567D02*
G03X64961Y1968504I-3937J0D01*
G01X68898Y1933071D02*
G03X72835Y1929134I3937J0D01*
G01X68898Y1933071D02*
G03X72835Y1929134I3937J0D01*
G01X68898Y1964567D02*
G03X64961Y1968504I-3937J0D01*
G01X72835Y1929134D02*
X202756D01*
G01X72835D02*
X202756D01*
G01X68898Y1964567D02*
Y1933071D01*
G01Y1964567D02*
Y1933071D01*
G01Y1964567D02*
G03X64961Y1968504I-3937J0D01*
G01X68898Y1933071D02*
Y1964567D01*
G01Y1933071D02*
G03X72835Y1929134I3937J0D01*
G01X202756D02*
X72835D01*
G01X80709Y1968504D02*
G03X76772Y1964567I0J-3937D01*
G01Y1960630D02*
Y1964567D01*
G01X168110Y1937008D02*
X76772D01*
G01X68898Y1960630D02*
G03X76772I3937J0D01*
G01Y1937008D02*
G03X68898I-3937J0D01*
G01Y1964567D02*
G03X64961Y1968504I-3937J0D01*
G01X68898Y1933071D02*
Y1964567D01*
G01Y1933071D02*
G03X72835Y1929134I3937J0D01*
G01X202756D02*
X72835D01*
G01X80709Y1968504D02*
G03X76772Y1964567I0J-3937D01*
G01Y1960630D02*
Y1964567D01*
G01X168110Y1937008D02*
X76772D01*
G01X68898Y1960630D02*
G03X76772I3937J0D01*
G01Y1937008D02*
G03X68898I-3937J0D01*
G01X80700Y0D02*
X340551D01*
G01X80700D02*
X340551D01*
G01X118011Y1968504D02*
X142520D01*
G01X109377D02*
X110137D01*
G01X109377D02*
X80709D01*
G01X110137D02*
G03X118011I3937J0D01*
G01X109377D02*
X80709D01*
G01X110137D02*
G03X118011I3937J0D01*
G01X168110Y31496D02*
G03Y39370I0J3937D01*
G01Y31496D02*
G03Y39370I0J3937D01*
G01X340559Y1968504D02*
X142520D01*
G01X168110Y1929134D02*
G03Y1937008I0J3937D01*
G01X340559Y1968504D02*
X142520D01*
G01X168110Y1929134D02*
G03Y1937008I0J3937D01*
G01X222441Y31496D02*
X198819D01*
G01X222441D02*
G03Y39370I0J3937D01*
G01X198819D02*
G03Y31496I0J-3937D01*
G01X222441D02*
X198819D01*
G01X222441D02*
G03Y39370I0J3937D01*
G01X198819D02*
G03Y31496I0J-3937D01*
G01X214567Y161417D02*
Y43307D01*
G01X202756Y39370D02*
G03X206693Y43307I0J3937D01*
G01X202756Y39370D02*
G03X206693Y43307I0J3937D01*
G01Y1925197D02*
Y43307D01*
G01Y1925197D02*
Y43307D01*
G01X202756Y39370D02*
G03X206693Y43307I0J3937D01*
G01X218504Y39370D02*
X348425D01*
G01X214567Y43307D02*
G03X218504Y39370I3937J0D01*
G01X202756D02*
G03X206693Y43307I0J3937D01*
G01X218504Y39370D02*
X348425D01*
G01X214567Y43307D02*
G03X218504Y39370I3937J0D01*
G01X206693Y161417D02*
Y1807087D01*
G01X214567D02*
Y161417D01*
G01Y169291D02*
G03X206693I-3937J0D01*
G01Y161417D02*
Y1807087D01*
G01X214567D02*
Y161417D01*
G01Y169291D02*
G03X206693I-3937J0D01*
G01Y200000D02*
G03X214567I3937J0D01*
G01X206693D02*
G03X214567I3937J0D01*
G01Y436220D02*
G03X206693I-3937J0D01*
G01X214567D02*
G03X206693I-3937J0D01*
G01Y466929D02*
G03X214567I3937J0D01*
G01X206693D02*
G03X214567I3937J0D01*
G01Y703149D02*
G03X206693I-3937J0D01*
G01Y733858D02*
G03X214567I3937J0D01*
G01Y703149D02*
G03X206693I-3937J0D01*
G01Y733858D02*
G03X214567I3937J0D01*
G01Y970867D02*
G03X206693I-3937J0D01*
G01Y997637D02*
G03X214567I3937J0D01*
G01Y970867D02*
G03X206693I-3937J0D01*
G01Y997637D02*
G03X214567I3937J0D01*
G01X206693Y1265355D02*
G03X214567I3937J0D01*
G01Y1234646D02*
G03X206693I-3937J0D01*
G01Y1265355D02*
G03X214567I3937J0D01*
G01Y1234646D02*
G03X206693I-3937J0D01*
G01X214567Y1501575D02*
G03X206693I-3937J0D01*
G01X214567D02*
G03X206693I-3937J0D01*
G01Y1532284D02*
G03X214567I3937J0D01*
G01X206693D02*
G03X214567I3937J0D01*
G01Y1768504D02*
G03X206693I-3937J0D01*
G01X214567D02*
G03X206693I-3937J0D01*
G01X214567Y1807087D02*
Y1925197D01*
G01X206693Y1799213D02*
G03X214567I3937J0D01*
G01X206693D02*
G03X214567I3937J0D01*
G01X206693Y1925197D02*
G03X202756Y1929134I-3937J0D01*
G01X206693Y1925197D02*
G03X202756Y1929134I-3937J0D01*
G01X206693Y1925197D02*
G03X202756Y1929134I-3937J0D01*
G01X218504D02*
G03X214567Y1925197I0J-3937D01*
G01X206693D02*
G03X202756Y1929134I-3937J0D01*
G01X218504D02*
G03X214567Y1925197I0J-3937D01*
G01X348425Y1929134D02*
X218504D01*
G01X198819Y1937008D02*
X222441D01*
G01X198819D02*
G03Y1929134I0J-3937D01*
G01X222441D02*
G03Y1937008I0J3937D01*
G01X348425Y1929134D02*
X218504D01*
G01X198819Y1937008D02*
X222441D01*
G01X198819D02*
G03Y1929134I0J-3937D01*
G01X222441D02*
G03Y1937008I0J3937D01*
G01X253150Y31496D02*
X344488D01*
G01X253150Y39370D02*
G03Y31496I0J-3937D01*
G01D02*
X344488D01*
G01X253150Y39370D02*
G03Y31496I0J-3937D01*
G01Y1937008D02*
X344496D01*
G01X253150D02*
G03Y1929134I0J-3937D01*
G01Y1937008D02*
X344496D01*
G01X253150D02*
G03Y1929134I0J-3937D01*
G01X356299Y0D02*
X417323D01*
G01X352362Y3937D02*
G03X356299Y0I3937J0D01*
G01X352362Y35433D02*
Y3937D01*
G01Y35433D02*
G03X348425Y39370I-3937J0D01*
G01X340551Y0D02*
G03X344488Y3937I0J3937D01*
G01Y7874D02*
Y3937D01*
G01X352362Y7874D02*
G03X344488I-3937J0D01*
G01Y31496D02*
G03X352362I3937J0D01*
G01X356299Y0D02*
X417323D01*
G01X352362Y3937D02*
G03X356299Y0I3937J0D01*
G01X352362Y35433D02*
Y3937D01*
G01Y35433D02*
G03X348425Y39370I-3937J0D01*
G01X340551Y0D02*
G03X344488Y3937I0J3937D01*
G01Y7874D02*
Y3937D01*
G01X352362Y7874D02*
G03X344488I-3937J0D01*
G01Y31496D02*
G03X352362I3937J0D01*
G01X348425Y1929134D02*
G03X352362Y1933071I0J3937D01*
G01Y1964567D02*
Y1933071D01*
G01X356299Y1968504D02*
G03X352362Y1964567I0J-3937D01*
G01X417323Y1968504D02*
X356299D01*
G01X344496Y1964567D02*
G03X340559Y1968504I-3937J0D01*
G01X344496Y1960889D02*
Y1964567D01*
G01Y1960889D02*
G03X352370I3937J0D01*
G01Y1937008D02*
G03X344496I-3937J0D01*
G01X348425Y1929134D02*
G03X352362Y1933071I0J3937D01*
G01Y1964567D02*
Y1933071D01*
G01X356299Y1968504D02*
G03X352362Y1964567I0J-3937D01*
G01X417323Y1968504D02*
X356299D01*
G01X344496Y1964567D02*
G03X340559Y1968504I-3937J0D01*
G01X344496Y1960889D02*
Y1964567D01*
G01Y1960889D02*
G03X352370I3937J0D01*
G01Y1937008D02*
G03X344496I-3937J0D01*
G01X429134Y3937D02*
G03X433071Y0I3937J0D01*
G01X429134Y1964567D02*
Y3937D01*
G01X433071Y0D02*
X494095D01*
G01X421260Y3937D02*
Y1964567D01*
G01X417323Y0D02*
G03X421260Y3937I0J3937D01*
G01X429134Y11811D02*
G03X421260I-3937J0D01*
G01X429134Y3937D02*
G03X433071Y0I3937J0D01*
G01X429134Y1964567D02*
Y3937D01*
G01X433071Y0D02*
X494095D01*
G01X421260Y3937D02*
Y1964567D01*
G01X417323Y0D02*
G03X421260Y3937I0J3937D01*
G01X429134Y11811D02*
G03X421260I-3937J0D01*
G01Y42520D02*
G03X429134I3937J0D01*
G01X421260D02*
G03X429134I3937J0D01*
G01Y278740D02*
G03X421260I-3937J0D01*
G01X429134D02*
G03X421260I-3937J0D01*
G01Y309449D02*
G03X429134I3937J0D01*
G01X421260D02*
G03X429134I3937J0D01*
G01Y545669D02*
G03X421260I-3937J0D01*
G01X429134D02*
G03X421260I-3937J0D01*
G01Y576378D02*
G03X429134I3937J0D01*
G01X421260D02*
G03X429134I3937J0D01*
G01Y831496D02*
G03X421260I-3937J0D01*
G01X429134D02*
G03X421260I-3937J0D01*
G01Y862205D02*
G03X429134I3937J0D01*
G01X421260D02*
G03X429134I3937J0D01*
G01Y1106299D02*
G03X421260I-3937J0D01*
G01X429134D02*
G03X421260I-3937J0D01*
G01Y1137008D02*
G03X429134I3937J0D01*
G01X421260D02*
G03X429134I3937J0D01*
G01Y1392126D02*
G03X421260I-3937J0D01*
G01X429134D02*
G03X421260I-3937J0D01*
G01Y1422835D02*
G03X429134I3937J0D01*
G01X421260D02*
G03X429134I3937J0D01*
G01Y1659055D02*
G03X421260I-3937J0D01*
G01X429134D02*
G03X421260I-3937J0D01*
G01Y1689764D02*
G03X429134I3937J0D01*
G01X421260D02*
G03X429134I3937J0D01*
G01Y1925984D02*
G03X421260I-3937J0D01*
G01X429134D02*
G03X421260I-3937J0D01*
G01X433071Y1968504D02*
G03X429134Y1964567I0J-3937D01*
G01X494095Y1968504D02*
X433071D01*
G01X421260Y1964567D02*
G03X417323Y1968504I-3937J0D01*
G01X421260Y1956693D02*
G03X429134I3937J0D01*
G01X433071Y1968504D02*
G03X429134Y1964567I0J-3937D01*
G01X494095Y1968504D02*
X433071D01*
G01X421260Y1964567D02*
G03X417323Y1968504I-3937J0D01*
G01X421260Y1956693D02*
G03X429134I3937J0D01*
G01X433071Y1968504D02*
G03X429134Y1964567I0J-3937D01*
G01X421260D02*
G03X417323Y1968504I-3937J0D01*
G01X501969Y39370D02*
G03X498032Y35433I0J-3937D01*
G01Y3937D02*
Y35433D01*
G01X494095Y0D02*
G03X498032Y3937I0J3937D01*
G01X505897Y0D02*
X648386D01*
G01X505897Y7615D02*
Y0D01*
G01X597244Y31496D02*
X505897D01*
G01Y7615D02*
G03X498023I-3937J0D01*
G01Y31496D02*
G03X505897I3937J0D01*
G01X501969Y39370D02*
G03X498032Y35433I0J-3937D01*
G01Y3937D02*
Y35433D01*
G01X494095Y0D02*
G03X498032Y3937I0J3937D01*
G01X505897Y0D02*
X620827D01*
G01X505897Y7615D02*
Y0D01*
G01X597244Y31496D02*
X505897D01*
G01Y7615D02*
G03X498023I-3937J0D01*
G01Y31496D02*
G03X505897I3937J0D01*
G01X501969Y39370D02*
X631890D01*
G01X501969D02*
X631890D01*
G01X498032Y1964567D02*
G03X494095Y1968504I-3937J0D01*
G01X498032Y1933071D02*
Y1960630D01*
G01Y1933071D02*
G03X501969Y1929134I3937J0D01*
G01X631890D02*
X501969D01*
G01X505906Y1960630D02*
Y1968504D01*
G01D02*
X648386D01*
G01X597244Y1937008D02*
X505906D01*
G01X498032Y1960630D02*
G03X505906I3937J0D01*
G01Y1937008D02*
G03X498032I-3937J0D01*
G01Y1964567D02*
G03X494095Y1968504I-3937J0D01*
G01X498032Y1933071D02*
Y1964567D01*
G01Y1933071D02*
G03X501969Y1929134I3937J0D01*
G01X631890D02*
X501969D01*
G01X505906Y1960630D02*
Y1968504D01*
G01D02*
X620827D01*
G01X597244Y1937008D02*
X505906D01*
G01X498032Y1960630D02*
G03X505906I3937J0D01*
G01Y1937008D02*
G03X498032I-3937J0D01*
G01X635827Y31496D02*
G03X643701Y39370I0J7874D01*
G01X650689Y19685D02*
G03I-6988J0D01*
G01X635827Y31496D02*
X627953D01*
G01X597244D02*
G03Y39370I0J3937D01*
G01X627953D02*
G03Y31496I0J-3937D01*
G01X650689Y19685D02*
G03I-6988J0D01*
G01X635827Y31496D02*
X627953D01*
G01X597244D02*
G03Y39370I0J3937D01*
G01X627953D02*
G03Y31496I0J-3937D01*
G01X635827Y161417D02*
Y43307D01*
G01X631890Y39370D02*
G03X635827Y43307I0J3937D01*
G01X631890Y39370D02*
G03X635827Y43307I0J3937D01*
G01X643701Y169256D02*
G03X635827I-3937J0D01*
G01X643701D02*
G03X635827I-3937J0D01*
G01Y161417D02*
Y1807087D01*
G01Y161417D02*
Y1807087D01*
G01Y199965D02*
G03X643701I3937J0D01*
G01X635827D02*
G03X643701I3937J0D01*
G01Y436186D02*
G03X635827I-3937J0D01*
G01X643701D02*
G03X635827I-3937J0D01*
G01Y466894D02*
G03X643701I3937J0D01*
G01X635827D02*
G03X643701I3937J0D01*
G01Y703115D02*
G03X635827I-3937J0D01*
G01Y733823D02*
G03X643701I3937J0D01*
G01Y703115D02*
G03X635827I-3937J0D01*
G01Y733823D02*
G03X643701I3937J0D01*
G01X635827Y997603D02*
G03X643701I3937J0D01*
G01Y970832D02*
G03X635827I-3937J0D01*
G01Y997603D02*
G03X643701I3937J0D01*
G01Y970832D02*
G03X635827I-3937J0D01*
G01Y1265320D02*
G03X643701I3937J0D01*
G01Y1234611D02*
G03X635827I-3937J0D01*
G01Y1265320D02*
G03X643701I3937J0D01*
G01Y1234611D02*
G03X635827I-3937J0D01*
G01X643701Y1501541D02*
G03X635827I-3937J0D01*
G01X643701D02*
G03X635827I-3937J0D01*
G01Y1532249D02*
G03X643701I3937J0D01*
G01X635827D02*
G03X643701I3937J0D01*
G01Y1768470D02*
G03X635827I-3937J0D01*
G01X643701D02*
G03X635827I-3937J0D01*
G01Y1799178D02*
G03X643701I3937J0D01*
G01X635827D02*
G03X643701I3937J0D01*
G01X635827Y1818898D02*
Y1807087D01*
G01Y1818898D02*
Y1925197D01*
G01Y1818898D02*
Y1925197D01*
G01D02*
G03X631890Y1929134I-3937J0D01*
G01X635827Y1925197D02*
G03X631890Y1929134I-3937J0D01*
G01X643701D02*
G03X635827Y1937008I-7874J0D01*
G01X650689Y1948819D02*
G03I-6988J0D01*
G01X627953Y1937008D02*
X635827D01*
G01X627953D02*
G03Y1929134I0J-3937D01*
G01X597244D02*
G03Y1937008I0J3937D01*
G01X650689Y1948819D02*
G03I-6988J0D01*
G01X627953Y1937008D02*
X635827D01*
G01X627953D02*
G03Y1929134I0J-3937D01*
G01X597244D02*
G03Y1937008I0J3937D01*
G01X650689Y1948819D02*
G03I-6988J0D01*
G01X648386Y0D02*
G03X663386Y15000I0J15000D01*
G01Y1953504D02*
Y15000D01*
G01X643701Y169256D02*
Y39370D01*
G01Y436186D02*
Y199965D01*
G01Y703115D02*
Y466894D01*
G01Y970832D02*
Y733823D01*
G01Y1234611D02*
Y997603D01*
G01Y1501541D02*
Y1265320D01*
G01Y1768470D02*
Y1532249D01*
G01Y1929134D02*
Y1799178D01*
G01X663386Y1953504D02*
G03X648386Y1968504I-15000J0D01*
M02*
